(kicad_pcb
	(version 20260206)
	(generator "pcbnew")
	(generator_version "10.0")
	(general
		(thickness 1.6)
		(legacy_teardrops no)
	)
	(paper "A4")
	(title_block
		(title "timecard-production-celestica-r4006 — R4006-B0001-02_R01.brd")
		(comment 1 "Time Appliance Project (Time Card) / footprints 67-72 of 1113")
	)
	(layers
		(0 "F.Cu" signal "TOP")
		(4 "In1.Cu" signal "L02_GND1")
		(6 "In2.Cu" signal "L03_SIG1")
		(8 "In3.Cu" signal "L04_GND2")
		(10 "In4.Cu" signal "L05_VCC1")
		(12 "In5.Cu" signal "L06_VCC2")
		(14 "In6.Cu" signal "L07_GND3")
		(16 "In7.Cu" signal "L08_SIG2")
		(18 "In8.Cu" signal "L09_GND4")
		(2 "B.Cu" signal "BOTTOM")
		(9 "F.Adhes" user "F.Adhesive")
		(11 "B.Adhes" user "B.Adhesive")
		(13 "F.Paste" user "Package Geometry/Pastemask Top")
		(15 "B.Paste" user "Package Geometry/Pastemask Bottom")
		(5 "F.SilkS" user "Ref Des/Silkscreen Top")
		(7 "B.SilkS" user "Ref Des/Silkscreen Bottom")
		(1 "F.Mask" user "Board Geometry/Soldermask Top")
		(3 "B.Mask" user "Board Geometry/Soldermask Bottom")
		(17 "Dwgs.User" user "User.Drawings")
		(19 "Cmts.User" user "User.Comments")
		(21 "Eco1.User" user "User.Eco1")
		(23 "Eco2.User" user "User.Eco2")
		(25 "Edge.Cuts" user "Board Geometry/Outline")
		(27 "Margin" user)
		(31 "F.CrtYd" user "Package Geometry/Place Bound Top")
		(29 "B.CrtYd" user "Package Geometry/Place Bound Bottom")
		(35 "F.Fab" user "Ref Des/Assembly Top")
		(33 "B.Fab" user "Ref Des/Assembly Bottom")
	)
	(footprint ""
		(layer "F.Cu")
		(at 80.3148 -84.201 180)
		(property "Reference" "U4"
			(at 0.3048 3.52933 0)
			(unlocked yes)
			(layer "F.SilkS")
			(effects
				(font
					(size 0.7874 0.5842)
					(thickness 0.1524)
				)
			)
		)
		(property "Value" ""
			(at 0 0 180)
			(layer "F.Fab")
			(effects
				(font
					(size 1.27 1.27)
				)
			)
		)
		(property "Device Type" "PCA9546APW_TSSOP16-G223-10280-A"
			(at 0 0.924306 180)
			(unlocked yes)
			(layer "F.Fab")
			(hide yes)
			(effects
				(font
					(size 0.7874 0.5842)
					(thickness 0.1524)
				)
			)
		)
		(property "User Part Number" "PARTNUM*"
			(at 0 1.940306 180)
			(unlocked yes)
			(layer "Cmts.User")
			(hide yes)
			(effects
				(font
					(size 0.7874 0.5842)
					(thickness 0.1524)
				)
			)
		)
		(duplicate_pad_numbers_are_jumpers no)
		(fp_line
			(start 4.0767 2.7559)
			(end -4.0767 2.7559)
			(stroke
				(width 0.1)
				(type default)
			)
			(layer "F.SilkS")
		)
		(fp_line
			(start 4.0767 -2.7559)
			(end 4.0767 2.7559)
			(stroke
				(width 0.1)
				(type default)
			)
			(layer "F.SilkS")
		)
		(fp_line
			(start -4.0767 2.7559)
			(end -4.0767 -2.7559)
			(stroke
				(width 0.1)
				(type default)
			)
			(layer "F.SilkS")
		)
		(fp_line
			(start -4.0767 -2.7559)
			(end 4.0767 -2.7559)
			(stroke
				(width 0.1)
				(type default)
			)
			(layer "F.SilkS")
		)
		(fp_poly
			(pts
				(arc
					(start -5.1435 -2.2225)
					(mid -4.3815 -2.2225)
					(end -5.1435 -2.2225)
				)
			)
			(stroke
				(width 0)
				(type default)
			)
			(fill yes)
			(layer "F.SilkS")
		)
		(fp_rect
			(start -4.3307 3.0099)
			(end 4.3307 -3.0099)
			(stroke
				(width 0)
				(type default)
			)
			(fill no)
			(layer "F.CrtYd")
		)
		(fp_line
			(start 2.1971 2.5019)
			(end -2.1971 2.5019)
			(stroke
				(width 0.1)
				(type default)
			)
			(layer "F.Fab")
		)
		(fp_line
			(start 2.1971 -2.5019)
			(end 2.1971 2.5019)
			(stroke
				(width 0.1)
				(type default)
			)
			(layer "F.Fab")
		)
		(fp_line
			(start -2.1971 2.5019)
			(end -2.1971 -2.5019)
			(stroke
				(width 0.1)
				(type default)
			)
			(layer "F.Fab")
		)
		(fp_line
			(start -2.1971 -2.5019)
			(end 2.1971 -2.5019)
			(stroke
				(width 0.1)
				(type default)
			)
			(layer "F.Fab")
		)
		(fp_poly
			(pts
				(arc
					(start -1.914652 -1.942084)
					(mid -1.114044 -1.941576)
					(end -1.914652 -1.942084)
				)
			)
			(stroke
				(width 0)
				(type default)
			)
			(fill yes)
			(layer "F.Fab")
		)
		(fp_text user "9"
			(at 4.5466 2.31267 180)
			(unlocked yes)
			(layer "F.SilkS")
			(effects
				(font
					(size 0.7874 0.5842)
					(thickness 0.1524)
				)
			)
		)
		(fp_text user "16"
			(at 2.8448 -3.72237 0)
			(unlocked yes)
			(layer "F.SilkS")
			(effects
				(font
					(size 0.7874 0.5842)
					(thickness 0.1524)
				)
			)
		)
		(fp_text user "8"
			(at -4.6482 2.11963 0)
			(unlocked yes)
			(layer "F.SilkS")
			(effects
				(font
					(size 0.7874 0.5842)
					(thickness 0.1524)
				)
			)
		)
		(fp_text user "16"
			(at 3.0988 -2.43967 0)
			(unlocked yes)
			(layer "F.Fab")
			(effects
				(font
					(size 0.7874 0.5842)
					(thickness 0.1524)
				)
			)
		)
		(fp_text user "9"
			(at 2.9718 2.25933 0)
			(unlocked yes)
			(layer "F.Fab")
			(effects
				(font
					(size 0.7874 0.5842)
					(thickness 0.1524)
				)
			)
		)
		(fp_text user "8"
			(at -2.7432 2.38633 0)
			(unlocked yes)
			(layer "F.Fab")
			(effects
				(font
					(size 0.7874 0.5842)
					(thickness 0.1524)
				)
			)
		)
		(pad "1" smd rect
			(at -3.0353 -2.275078 270)
			(size 0.3556 1.5748)
			(layers "F.Cu" "F.Mask" "F.Paste")
			(net "UNNAMED_5_PCA9546APWTSSOP16_I33")
		)
		(pad "2" smd rect
			(at -3.0353 -1.625092 270)
			(size 0.3556 1.5748)
			(layers "F.Cu" "F.Mask" "F.Paste")
			(net "UNNAMED_5_PCA9546APWTSSOP16_I_1")
		)
		(pad "3" smd rect
			(at -3.0353 -0.975106 270)
			(size 0.3556 1.5748)
			(layers "F.Cu" "F.Mask" "F.Paste")
			(net "PCA9546_RST_N")
		)
		(pad "4" smd rect
			(at -3.0353 -0.32512 270)
			(size 0.3556 1.5748)
			(layers "F.Cu" "F.Mask" "F.Paste")
			(net "LM75B_I2C_SDA")
		)
		(pad "5" smd rect
			(at -3.0353 0.32512 270)
			(size 0.3556 1.5748)
			(layers "F.Cu" "F.Mask" "F.Paste")
			(net "LM75B_I2C_SCL")
		)
		(pad "6" smd rect
			(at -3.0353 0.975106 270)
			(size 0.3556 1.5748)
			(layers "F.Cu" "F.Mask" "F.Paste")
			(net "SHT3X_I2C_SDA")
		)
		(pad "7" smd rect
			(at -3.0353 1.625092 270)
			(size 0.3556 1.5748)
			(layers "F.Cu" "F.Mask" "F.Paste")
			(net "SHT3X_I2C_SCL")
		)
		(pad "8" smd rect
			(at -3.0353 2.275078 270)
			(size 0.3556 1.5748)
			(layers "F.Cu" "F.Mask" "F.Paste")
			(net "SG")
		)
		(pad "9" smd rect
			(at 3.0353 2.275078 270)
			(size 0.3556 1.5748)
			(layers "F.Cu" "F.Mask" "F.Paste")
			(net "ICP10100_I2C_SDA")
		)
		(pad "10" smd rect
			(at 3.0353 1.625092 270)
			(size 0.3556 1.5748)
			(layers "F.Cu" "F.Mask" "F.Paste")
			(net "ICP10100_I2C_SCL")
		)
		(pad "11" smd rect
			(at 3.0353 0.975106 270)
			(size 0.3556 1.5748)
			(layers "F.Cu" "F.Mask" "F.Paste")
			(net "BNO080_I2C_SDA")
		)
		(pad "12" smd rect
			(at 3.0353 0.32512 270)
			(size 0.3556 1.5748)
			(layers "F.Cu" "F.Mask" "F.Paste")
			(net "BNO080_I2C_SCL")
		)
		(pad "13" smd rect
			(at 3.0353 -0.32512 270)
			(size 0.3556 1.5748)
			(layers "F.Cu" "F.Mask" "F.Paste")
			(net "UNNAMED_5_PCA9546APWTSSOP16_I_2")
		)
		(pad "14" smd rect
			(at 3.0353 -0.975106 270)
			(size 0.3556 1.5748)
			(layers "F.Cu" "F.Mask" "F.Paste")
			(net "R_PCA9546_I2C_SCL")
		)
		(pad "15" smd rect
			(at 3.0353 -1.625092 270)
			(size 0.3556 1.5748)
			(layers "F.Cu" "F.Mask" "F.Paste")
			(net "R_PCA9546_I2C_SDA")
		)
		(pad "16" smd rect
			(at 3.0353 -2.275078 270)
			(size 0.3556 1.5748)
			(layers "F.Cu" "F.Mask" "F.Paste")
			(net "VDD_PCA9546A")
		)
	)
	(footprint ""
		(layer "F.Cu")
		(at 138.050016 -107.849924 -90)
		(property "Reference" "DS1"
			(at -0.100076 1.866646 90)
			(unlocked yes)
			(layer "F.SilkS")
			(effects
				(font
					(size 0.7874 0.5842)
					(thickness 0.1524)
				)
			)
		)
		(property "Value" ""
			(at 0 0 270)
			(layer "F.Fab")
			(effects
				(font
					(size 1.27 1.27)
				)
			)
		)
		(property "User Part Number" "PARTNUM*"
			(at 0.1778 2.422881 270)
			(unlocked yes)
			(layer "Cmts.User")
			(hide yes)
			(effects
				(font
					(size 0.786892 0.583946)
					(thickness 0.000001)
				)
			)
		)
		(property "Device Type" "OPTICAL-G170-10143-01"
			(at 0.1778 1.483081 270)
			(unlocked yes)
			(layer "F.Fab")
			(hide yes)
			(effects
				(font
					(size 0.786892 0.583946)
					(thickness 0.000001)
				)
			)
		)
		(duplicate_pad_numbers_are_jumpers no)
		(fp_line
			(start -1.3208 1.2192)
			(end -2.5908 1.2192)
			(stroke
				(width 0.1)
				(type default)
			)
			(layer "F.SilkS")
		)
		(fp_line
			(start -1.397508 0.704088)
			(end -1.397508 -0.704088)
			(stroke
				(width 0.1)
				(type default)
			)
			(layer "F.SilkS")
		)
		(fp_line
			(start 1.397508 0.704088)
			(end -1.397508 0.704088)
			(stroke
				(width 0.1)
				(type default)
			)
			(layer "F.SilkS")
		)
		(fp_line
			(start -1.9558 0.5842)
			(end -1.9558 1.8542)
			(stroke
				(width 0.1)
				(type default)
			)
			(layer "F.SilkS")
		)
		(fp_line
			(start -1.397508 -0.704088)
			(end 1.397508 -0.704088)
			(stroke
				(width 0.1)
				(type default)
			)
			(layer "F.SilkS")
		)
		(fp_line
			(start 1.397508 -0.704088)
			(end 1.397508 0.704088)
			(stroke
				(width 0.1)
				(type default)
			)
			(layer "F.SilkS")
		)
		(fp_rect
			(start 1.905508 0.704088)
			(end 1.397508 -0.704088)
			(stroke
				(width 0)
				(type default)
			)
			(fill yes)
			(layer "F.SilkS")
		)
		(fp_rect
			(start 1.905508 0.958088)
			(end -1.651508 -0.958088)
			(stroke
				(width 0)
				(type default)
			)
			(fill no)
			(layer "F.CrtYd")
		)
		(fp_line
			(start -1.3208 1.0922)
			(end -2.5908 1.0922)
			(stroke
				(width 0.1)
				(type default)
			)
			(layer "F.Fab")
		)
		(fp_line
			(start -1.9558 0.4572)
			(end -1.9558 1.7272)
			(stroke
				(width 0.1)
				(type default)
			)
			(layer "F.Fab")
		)
		(fp_line
			(start -0.850138 0.450088)
			(end 0.850138 0.450088)
			(stroke
				(width 0.1)
				(type default)
			)
			(layer "F.Fab")
		)
		(fp_line
			(start 0.850138 0.450088)
			(end 0.850138 -0.450088)
			(stroke
				(width 0.1)
				(type default)
			)
			(layer "F.Fab")
		)
		(fp_line
			(start -0.850138 -0.450088)
			(end -0.850138 0.450088)
			(stroke
				(width 0.1)
				(type default)
			)
			(layer "F.Fab")
		)
		(fp_line
			(start 0.850138 -0.450088)
			(end -0.850138 -0.450088)
			(stroke
				(width 0.1)
				(type default)
			)
			(layer "F.Fab")
		)
		(fp_rect
			(start 0.850138 0.450088)
			(end 0.342138 -0.450088)
			(stroke
				(width 0)
				(type default)
			)
			(fill yes)
			(layer "F.Fab")
		)
		(fp_text user "C"
			(at 1.582674 1.398016 0)
			(unlocked yes)
			(layer "F.SilkS")
			(effects
				(font
					(size 0.635 0.4064)
					(thickness 0.1524)
				)
			)
		)
		(fp_text user "A"
			(at -2.024126 0.382016 0)
			(unlocked yes)
			(layer "F.SilkS")
			(effects
				(font
					(size 0.635 0.4064)
					(thickness 0.1524)
				)
			)
		)
		(fp_text user "A"
			(at -1.700276 0.255016 0)
			(unlocked yes)
			(layer "F.Fab")
			(effects
				(font
					(size 0.7874 0.5842)
					(thickness 0.1524)
				)
			)
		)
		(fp_text user "C"
			(at 1.082294 -0.887984 0)
			(unlocked yes)
			(layer "F.Fab")
			(effects
				(font
					(size 0.7874 0.5842)
					(thickness 0.1524)
				)
			)
		)
		(pad "A" smd rect
			(at -0.749808 0 270)
			(size 0.7874 0.7874)
			(layers "F.Cu" "F.Mask" "F.Paste")
			(net "UNNAMED_14_OPTICAL_I12_A")
		)
		(pad "C" smd rect
			(at 0.749808 0 270)
			(size 0.7874 0.7874)
			(layers "F.Cu" "F.Mask" "F.Paste")
			(net "LED_DATOUT3")
		)
	)
	(footprint ""
		(layer "F.Cu")
		(at 12.1412 -65.786 90)
		(property "Reference" "R371"
			(at 5.334 -0.29083 90)
			(unlocked yes)
			(layer "F.SilkS")
			(effects
				(font
					(size 0.7874 0.5842)
					(thickness 0.1524)
				)
			)
		)
		(property "Value" "VAL*"
			(at 0.02032 2.13233 90)
			(unlocked yes)
			(layer "F.Fab")
			(hide yes)
			(effects
				(font
					(size 0.7874 0.5842)
					(thickness 0.1524)
				)
			)
		)
		(property "Tolerance" "TOL*"
			(at 0.044704 3.05435 90)
			(unlocked yes)
			(layer "Cmts.User")
			(hide yes)
			(effects
				(font
					(size 0.7874 0.5842)
					(thickness 0.1524)
				)
			)
		)
		(property "User Part Number" "PARTNUM*"
			(at 0.02032 4.024884 90)
			(unlocked yes)
			(layer "Cmts.User")
			(hide yes)
			(effects
				(font
					(size 0.7874 0.5842)
					(thickness 0.1524)
				)
			)
		)
		(property "Device Type" "RESISTOR-G155-149R9-01,49.9OHMA"
			(at 0.008382 1.210564 90)
			(unlocked yes)
			(layer "F.Fab")
			(hide yes)
			(effects
				(font
					(size 0.7874 0.5842)
					(thickness 0.1524)
				)
			)
		)
		(duplicate_pad_numbers_are_jumpers no)
		(fp_line
			(start 1.143 -0.5588)
			(end -1.143 -0.5588)
			(stroke
				(width 0.1)
				(type default)
			)
			(layer "F.SilkS")
		)
		(fp_line
			(start -1.143 -0.5588)
			(end -1.143 0.5588)
			(stroke
				(width 0.1)
				(type default)
			)
			(layer "F.SilkS")
		)
		(fp_line
			(start 1.143 0.5588)
			(end 1.143 -0.5588)
			(stroke
				(width 0.1)
				(type default)
			)
			(layer "F.SilkS")
		)
		(fp_line
			(start -1.143 0.5588)
			(end 1.143 0.5588)
			(stroke
				(width 0.1)
				(type default)
			)
			(layer "F.SilkS")
		)
		(fp_poly
			(pts
				(xy -1.143 0.5588) (xy 1.143 0.5588) (xy 1.143 -0.5588) (xy -1.143 -0.5588)
			)
			(stroke
				(width 0)
				(type default)
			)
			(fill no)
			(layer "F.CrtYd")
		)
		(fp_line
			(start 0.508 -0.3048)
			(end -0.508 -0.3048)
			(stroke
				(width 0.1)
				(type default)
			)
			(layer "F.Fab")
		)
		(fp_line
			(start -0.508 -0.3048)
			(end -0.508 0.3048)
			(stroke
				(width 0.1)
				(type default)
			)
			(layer "F.Fab")
		)
		(fp_line
			(start 0.508 0.3048)
			(end 0.508 -0.3048)
			(stroke
				(width 0.1)
				(type default)
			)
			(layer "F.Fab")
		)
		(fp_line
			(start -0.508 0.3048)
			(end 0.508 0.3048)
			(stroke
				(width 0.1)
				(type default)
			)
			(layer "F.Fab")
		)
		(pad "1" smd rect
			(at -0.5334 0 90)
			(size 0.7112 0.6096)
			(layers "F.Cu" "F.Mask" "F.Paste")
			(net "BF_ANT1_IN")
		)
		(pad "2" smd rect
			(at 0.5334 0 90)
			(size 0.7112 0.6096)
			(layers "F.Cu" "F.Mask" "F.Paste")
			(net "ANT1_IN")
		)
		(zone
			(layer "F.Cu")
			(hatch none 0.5)
			(connect_pads
				(clearance 0)
			)
			(min_thickness 0.25)
			(keepout
				(tracks allowed)
				(vias not_allowed)
				(pads allowed)
				(copperpour not_allowed)
				(footprints allowed)
			)
			(placement
				(enabled no)
				(sheetname "")
			)
			(fill
				(thermal_gap 0.5)
				(thermal_bridge_width 0.5)
				(island_removal_mode 0)
			)
			(polygon
				(pts
					(xy 12.446 -65.7098) (xy 12.446 -65.8622) (xy 11.8364 -65.8622) (xy 11.8364 -65.7098)
				)
			)
		)
		(zone
			(layer "F.Cu")
			(hatch none 0.5)
			(connect_pads
				(clearance 0)
			)
			(min_thickness 0.25)
			(keepout
				(tracks not_allowed)
				(vias allowed)
				(pads allowed)
				(copperpour not_allowed)
				(footprints allowed)
			)
			(placement
				(enabled no)
				(sheetname "")
			)
			(fill
				(thermal_gap 0.5)
				(thermal_bridge_width 0.5)
				(island_removal_mode 0)
			)
			(polygon
				(pts
					(xy 12.446 -65.7098) (xy 12.446 -65.8622) (xy 11.8364 -65.8622) (xy 11.8364 -65.7098)
				)
			)
		)
	)
	(footprint ""
		(layer "F.Cu")
		(at 80.772 -61.8236)
		(property "Reference" "R306"
			(at -10.287 -19.51863 0)
			(unlocked yes)
			(layer "F.SilkS")
			(effects
				(font
					(size 0.7874 0.5842)
					(thickness 0.1524)
				)
			)
		)
		(property "Value" "VAL*"
			(at 0.02032 2.13233 0)
			(unlocked yes)
			(layer "F.Fab")
			(hide yes)
			(effects
				(font
					(size 0.7874 0.5842)
					(thickness 0.1524)
				)
			)
		)
		(property "Tolerance" "TOL*"
			(at 0.044704 3.05435 0)
			(unlocked yes)
			(layer "Cmts.User")
			(hide yes)
			(effects
				(font
					(size 0.7874 0.5842)
					(thickness 0.1524)
				)
			)
		)
		(property "User Part Number" "PARTNUM*"
			(at 0.02032 4.024884 0)
			(unlocked yes)
			(layer "Cmts.User")
			(hide yes)
			(effects
				(font
					(size 0.7874 0.5842)
					(thickness 0.1524)
				)
			)
		)
		(property "Device Type" "RESISTOR-G155-14701-01,4.7KOHMA"
			(at 0.008382 1.210564 0)
			(unlocked yes)
			(layer "F.Fab")
			(hide yes)
			(effects
				(font
					(size 0.7874 0.5842)
					(thickness 0.1524)
				)
			)
		)
		(duplicate_pad_numbers_are_jumpers no)
		(fp_line
			(start -1.143 -0.5588)
			(end -1.143 0.5588)
			(stroke
				(width 0.1)
				(type default)
			)
			(layer "F.SilkS")
		)
		(fp_line
			(start -1.143 0.5588)
			(end 1.143 0.5588)
			(stroke
				(width 0.1)
				(type default)
			)
			(layer "F.SilkS")
		)
		(fp_line
			(start 1.143 -0.5588)
			(end -1.143 -0.5588)
			(stroke
				(width 0.1)
				(type default)
			)
			(layer "F.SilkS")
		)
		(fp_line
			(start 1.143 0.5588)
			(end 1.143 -0.5588)
			(stroke
				(width 0.1)
				(type default)
			)
			(layer "F.SilkS")
		)
		(fp_rect
			(start -1.143 0.5588)
			(end 1.143 -0.5588)
			(stroke
				(width 0)
				(type default)
			)
			(fill no)
			(layer "F.CrtYd")
		)
		(fp_line
			(start -0.508 -0.3048)
			(end -0.508 0.3048)
			(stroke
				(width 0.1)
				(type default)
			)
			(layer "F.Fab")
		)
		(fp_line
			(start -0.508 0.3048)
			(end 0.508 0.3048)
			(stroke
				(width 0.1)
				(type default)
			)
			(layer "F.Fab")
		)
		(fp_line
			(start 0.508 -0.3048)
			(end -0.508 -0.3048)
			(stroke
				(width 0.1)
				(type default)
			)
			(layer "F.Fab")
		)
		(fp_line
			(start 0.508 0.3048)
			(end 0.508 -0.3048)
			(stroke
				(width 0.1)
				(type default)
			)
			(layer "F.Fab")
		)
		(pad "1" smd rect
			(at -0.5334 0)
			(size 0.7112 0.6096)
			(layers "F.Cu" "F.Mask" "F.Paste")
			(net "XP3R3V_FPGA")
		)
		(pad "2" smd rect
			(at 0.5334 0)
			(size 0.7112 0.6096)
			(layers "F.Cu" "F.Mask" "F.Paste")
			(net "UNNAMED_9_BNO080LGA28_I29_CLKSE")
		)
		(zone
			(layer "F.Cu")
			(hatch none 0.5)
			(connect_pads
				(clearance 0)
			)
			(min_thickness 0.25)
			(keepout
				(tracks allowed)
				(vias not_allowed)
				(pads allowed)
				(copperpour not_allowed)
				(footprints allowed)
			)
			(placement
				(enabled no)
				(sheetname "")
			)
			(fill
				(thermal_gap 0.5)
				(thermal_bridge_width 0.5)
				(island_removal_mode 0)
			)
			(polygon
				(pts
					(xy 80.6958 -61.5188) (xy 80.8482 -61.5188) (xy 80.8482 -62.1284) (xy 80.6958 -62.1284)
				)
			)
		)
	)
	(footprint ""
		(layer "F.Cu")
		(at 55.88 -131.572)
		(property "Reference" "SP71"
			(at 0 0 0)
			(layer "F.SilkS")
			(hide yes)
			(effects
				(font
					(size 1.27 1.27)
				)
			)
		)
		(property "Value" ""
			(at 0 0 0)
			(layer "F.Fab")
			(effects
				(font
					(size 1.27 1.27)
				)
			)
		)
		(duplicate_pad_numbers_are_jumpers no)
	)
	(footprint ""
		(layer "F.Cu")
		(at 120.346978 -38.323266)
		(property "Reference" "TP133"
			(at 0 0 0)
			(layer "F.SilkS")
			(hide yes)
			(effects
				(font
					(size 1.27 1.27)
				)
			)
		)
		(property "Value" ""
			(at 0 0 0)
			(layer "F.Fab")
			(effects
				(font
					(size 1.27 1.27)
				)
			)
		)
		(property "Device Type" "TP_PIONT-TP010CT020B030_PTH-TPA"
			(at -1.341882 0.996696 0)
			(unlocked yes)
			(layer "F.Fab")
			(hide yes)
			(effects
				(font
					(size 0.7874 0.5842)
					(thickness 0.1524)
				)
				(justify left)
			)
		)
		(duplicate_pad_numbers_are_jumpers no)
		(fp_poly
			(pts
				(arc
					(start 0.889 0)
					(mid -0.889 0)
					(end 0.889 0)
				)
			)
			(stroke
				(width 0)
				(type default)
			)
			(fill no)
			(layer "B.CrtYd")
		)
		(fp_poly
			(pts
				(arc
					(start 0.889 0)
					(mid -0.889 0)
					(end 0.889 0)
				)
			)
			(stroke
				(width 0)
				(type default)
			)
			(fill no)
			(layer "F.CrtYd")
		)
		(pad "1" thru_hole circle
			(at 0 0)
			(size 0.508 0.508)
			(drill 0.254)
			(layers "*.Cu" "*.Mask")
			(remove_unused_layers no)
			(net "IO_L20N_34")
			(clearance 0.1016)
			(padstack
				(mode front_inner_back)
				(layer "Inner"
					(shape circle)
					(size 0.508 0.508)
					(clearance 0.1016)
				)
				(layer "B.Cu"
					(shape circle)
					(size 0.762 0.762)
					(clearance -0.0254)
				)
			)
		)
	)
)
